# S9S_MB_2U (Grand Teton) — schematic netlist excerpt (pin names and nets, part order shuffled) for the footprints in the layout excerpt that follows; sources: Cadence DE-HDL packaged netlist, KiCad conversion of 03242023_DA0F0TMBIJ0_F0T_Motherboard_J_brd_V01_OCP.brd

PC576  Q_CAP  22UF 16V 20% X6S  pkg C0805  page 259 : A = SW_P3V3_AUX_FLT ; B = GND
R2514  Q_RES  1K 1% EMPTY  pkg 0402LF  page 239 : A = PU_GTL2014_BMC_JTAG_DIR_1 ; B = GND
C833  Q_CAP_DIFFBUS  DIFF BUS_0.22UF 6.3V 20% X6S  pkg C0201  page 175 : \1\ = P5E_CPU1_PE1_TX_C_DP<2> ; \2\ = P5E_CPU1_PE1_TX_DP<2>

(kicad_pcb
	(version 20260206)
	(generator "pcbnew")
	(generator_version "10.0")
	(general
		(thickness 1.6)
		(legacy_teardrops no)
	)
	(paper "A4")
	(title_block
		(title "03242023_DA0F0TMBIJ0_F0T_Motherboard_J_brd_V01_OCP.brd")
		(comment 1 "Grand Teton / footprints 4134-4136 of 6105")
	)
	(layers
		(0 "F.Cu" signal "TOP")
		(4 "In1.Cu" signal "GND")
		(6 "In2.Cu" signal "IN1")
		(8 "In3.Cu" signal "GND1")
		(10 "In4.Cu" signal "IN2")
		(12 "In5.Cu" signal "GND2")
		(14 "In6.Cu" signal "IN3")
		(16 "In7.Cu" signal "GND3")
		(18 "In8.Cu" signal "VCC")
		(20 "In9.Cu" signal "VCC1")
		(22 "In10.Cu" signal "GND4")
		(24 "In11.Cu" signal "IN4")
		(26 "In12.Cu" signal "GND5")
		(28 "In13.Cu" signal "IN5")
		(30 "In14.Cu" signal "GND6")
		(32 "In15.Cu" signal "IN6")
		(34 "In16.Cu" signal "GND7")
		(2 "B.Cu" signal "BOTTOM")
		(9 "F.Adhes" user "F.Adhesive")
		(11 "B.Adhes" user "B.Adhesive")
		(13 "F.Paste" user "Package Geometry/Pastemask Top")
		(15 "B.Paste" user "Package Geometry/Pastemask Bottom")
		(5 "F.SilkS" user "Ref Des/Silkscreen Top")
		(7 "B.SilkS" user "Ref Des/Silkscreen Bottom")
		(1 "F.Mask" user "Board Geometry/Soldermask Top")
		(3 "B.Mask" user "Board Geometry/Soldermask Bottom")
		(17 "Dwgs.User" user "User.Drawings")
		(19 "Cmts.User" user "User.Comments")
		(21 "Eco1.User" user "User.Eco1")
		(23 "Eco2.User" user "User.Eco2")
		(25 "Edge.Cuts" user "Board Geometry/Outline")
		(27 "Margin" user)
		(31 "F.CrtYd" user "Package Geometry/Place Bound Top")
		(29 "B.CrtYd" user "Package Geometry/Place Bound Bottom")
		(35 "F.Fab" user "Ref Des/Assembly Top")
		(33 "B.Fab" user "Ref Des/Assembly Bottom")
	)
	(footprint ""
		(layer "F.Cu")
		(at 367.227358 -92.962984 -90)
		(property "Reference" "R2514"
			(at 0 0 270)
			(layer "F.SilkS")
			(hide yes)
			(effects
				(font
					(size 1.27 1.27)
				)
			)
		)
		(property "Value" ""
			(at 0 0 270)
			(layer "F.Fab")
			(effects
				(font
					(size 1.27 1.27)
				)
			)
		)
		(duplicate_pad_numbers_are_jumpers no)
		(fp_line
			(start -0.7874 0.4064)
			(end -0.7874 -0.4064)
			(stroke
				(width 0.1524)
				(type default)
			)
			(layer "F.SilkS")
		)
		(fp_line
			(start 0.7874 0.4064)
			(end -0.7874 0.4064)
			(stroke
				(width 0.1524)
				(type default)
			)
			(layer "F.SilkS")
		)
		(fp_line
			(start -0.7874 -0.4064)
			(end 0.7874 -0.4064)
			(stroke
				(width 0.1524)
				(type default)
			)
			(layer "F.SilkS")
		)
		(fp_line
			(start 0.7874 -0.4064)
			(end 0.7874 0.4064)
			(stroke
				(width 0.1524)
				(type default)
			)
			(layer "F.SilkS")
		)
		(fp_line
			(start -0.67945 0.3048)
			(end -0.67945 -0.305054)
			(stroke
				(width 0.1)
				(type default)
			)
			(layer "F.Fab")
		)
		(fp_line
			(start -0.12065 0.3048)
			(end -0.67945 0.3048)
			(stroke
				(width 0.1)
				(type default)
			)
			(layer "F.Fab")
		)
		(fp_line
			(start 0.120396 0.3048)
			(end 0.120396 0.2794)
			(stroke
				(width 0.1)
				(type default)
			)
			(layer "F.Fab")
		)
		(fp_line
			(start 0.67945 0.3048)
			(end 0.120396 0.3048)
			(stroke
				(width 0.1)
				(type default)
			)
			(layer "F.Fab")
		)
		(fp_line
			(start -0.12065 0.2794)
			(end -0.12065 0.3048)
			(stroke
				(width 0.1)
				(type default)
			)
			(layer "F.Fab")
		)
		(fp_line
			(start 0.120396 0.2794)
			(end -0.12065 0.2794)
			(stroke
				(width 0.1)
				(type default)
			)
			(layer "F.Fab")
		)
		(fp_line
			(start -0.12065 -0.2794)
			(end 0.12065 -0.2794)
			(stroke
				(width 0.1)
				(type default)
			)
			(layer "F.Fab")
		)
		(fp_line
			(start 0.12065 -0.2794)
			(end 0.12065 -0.3048)
			(stroke
				(width 0.1)
				(type default)
			)
			(layer "F.Fab")
		)
		(fp_line
			(start 0.12065 -0.3048)
			(end 0.67945 -0.3048)
			(stroke
				(width 0.1)
				(type default)
			)
			(layer "F.Fab")
		)
		(fp_line
			(start 0.67945 -0.3048)
			(end 0.67945 0.3048)
			(stroke
				(width 0.1)
				(type default)
			)
			(layer "F.Fab")
		)
		(fp_line
			(start -0.67945 -0.305054)
			(end -0.12065 -0.305054)
			(stroke
				(width 0.1)
				(type default)
			)
			(layer "F.Fab")
		)
		(fp_line
			(start -0.12065 -0.305054)
			(end -0.12065 -0.2794)
			(stroke
				(width 0.1)
				(type default)
			)
			(layer "F.Fab")
		)
		(pad "1" smd circle
			(at -0.40005 0 270)
			(size 0 0)
			(layers "F.Cu" "F.Mask" "F.Paste")
			(net "PU_GTL2014_BMC_JTAG_DIR_1")
		)
		(pad "2" smd circle
			(at 0.40005 0 270)
			(size 0 0)
			(layers "F.Cu" "F.Mask" "F.Paste")
			(net "GND")
		)
	)
	(footprint ""
		(layer "F.Cu")
		(at 53.08473 -17.623536 90)
		(property "Reference" "C833"
			(at 0 0 90)
			(layer "F.SilkS")
			(hide yes)
			(effects
				(font
					(size 1.27 1.27)
				)
			)
		)
		(property "Value" ""
			(at 0 0 90)
			(layer "F.Fab")
			(effects
				(font
					(size 1.27 1.27)
				)
			)
		)
		(duplicate_pad_numbers_are_jumpers no)
		(fp_line
			(start 0.299974 -0.150114)
			(end 0.299974 0.150114)
			(stroke
				(width 0.1)
				(type default)
			)
			(layer "F.Fab")
		)
		(fp_line
			(start -0.299974 -0.150114)
			(end 0.299974 -0.150114)
			(stroke
				(width 0.1)
				(type default)
			)
			(layer "F.Fab")
		)
		(fp_line
			(start 0.299974 0.150114)
			(end -0.299974 0.150114)
			(stroke
				(width 0.1)
				(type default)
			)
			(layer "F.Fab")
		)
		(fp_line
			(start -0.299974 0.150114)
			(end -0.299974 -0.150114)
			(stroke
				(width 0.1)
				(type default)
			)
			(layer "F.Fab")
		)
		(pad "1" smd rect
			(at -0.2667 0 90)
			(size 0.3048 0.381)
			(layers "F.Cu" "F.Mask" "F.Paste")
			(net "P5E_CPU1_PE1_TX_C_DP<2>")
		)
		(pad "2" smd rect
			(at 0.2667 0 90)
			(size 0.3048 0.381)
			(layers "F.Cu" "F.Mask" "F.Paste")
			(net "P5E_CPU1_PE1_TX_DP<2>")
		)
	)
	(footprint ""
		(layer "F.Cu")
		(at 456.520804 -76.588112 90)
		(property "Reference" "PC576"
			(at 0 0 90)
			(layer "F.SilkS")
			(hide yes)
			(effects
				(font
					(size 1.27 1.27)
				)
			)
		)
		(property "Value" ""
			(at 0 0 90)
			(layer "F.Fab")
			(effects
				(font
					(size 1.27 1.27)
				)
			)
		)
		(duplicate_pad_numbers_are_jumpers no)
		(fp_line
			(start 1.524 -0.762)
			(end 1.524 0.762)
			(stroke
				(width 0.1524)
				(type default)
			)
			(layer "F.SilkS")
		)
		(fp_line
			(start -1.524 -0.762)
			(end 1.524 -0.762)
			(stroke
				(width 0.1524)
				(type default)
			)
			(layer "F.SilkS")
		)
		(fp_line
			(start 1.524 0.762)
			(end -1.524 0.762)
			(stroke
				(width 0.1524)
				(type default)
			)
			(layer "F.SilkS")
		)
		(fp_line
			(start -1.524 0.762)
			(end -1.524 -0.762)
			(stroke
				(width 0.1524)
				(type default)
			)
			(layer "F.SilkS")
		)
		(fp_line
			(start 1.1049 -0.724916)
			(end -1.1049 -0.724916)
			(stroke
				(width 0.1)
				(type default)
			)
			(layer "F.Fab")
		)
		(fp_line
			(start -1.1049 -0.724916)
			(end -1.1049 0.724916)
			(stroke
				(width 0.1)
				(type default)
			)
			(layer "F.Fab")
		)
		(fp_line
			(start 1.1049 0.724916)
			(end 1.1049 -0.724916)
			(stroke
				(width 0.1)
				(type default)
			)
			(layer "F.Fab")
		)
		(fp_line
			(start -1.1049 0.724916)
			(end 1.1049 0.724916)
			(stroke
				(width 0.1)
				(type default)
			)
			(layer "F.Fab")
		)
		(pad "1" smd rect
			(at -0.889 0 270)
			(size 1.016 1.27)
			(layers "F.Cu" "F.Mask" "F.Paste")
			(net "SW_P3V3_AUX_FLT")
		)
		(pad "2" smd rect
			(at 0.889 0 270)
			(size 1.016 1.27)
			(layers "F.Cu" "F.Mask" "F.Paste")
			(net "GND")
		)
	)
)
